(kicad_pcb
	(version 20260206)
	(generator "pcbnew")
	(generator_version "10.0")
	(general
		(thickness 1.6)
		(legacy_teardrops no)
	)
	(paper "A4")
	(title_block
		(title "9054_F0T_PDB_BD_GPU_F_V04_1213_1550_OCP.brd")
		(comment 1 "Grand Teton / footprints 8-14 of 608")
	)
	(layers
		(0 "F.Cu" signal "TOP")
		(4 "In1.Cu" signal "GND")
		(6 "In2.Cu" signal "IN1")
		(8 "In3.Cu" signal "GND1")
		(10 "In4.Cu" signal "VCC")
		(12 "In5.Cu" signal "VCC1")
		(14 "In6.Cu" signal "GND2")
		(16 "In7.Cu" signal "IN2")
		(18 "In8.Cu" signal "GND3")
		(2 "B.Cu" signal "BOTTOM")
		(9 "F.Adhes" user "F.Adhesive")
		(11 "B.Adhes" user "B.Adhesive")
		(13 "F.Paste" user "Package Geometry/Pastemask Top")
		(15 "B.Paste" user "Package Geometry/Pastemask Bottom")
		(5 "F.SilkS" user "Ref Des/Silkscreen Top")
		(7 "B.SilkS" user "Ref Des/Silkscreen Bottom")
		(1 "F.Mask" user "Board Geometry/Soldermask Top")
		(3 "B.Mask" user "Board Geometry/Soldermask Bottom")
		(17 "Dwgs.User" user "User.Drawings")
		(19 "Cmts.User" user "User.Comments")
		(21 "Eco1.User" user "User.Eco1")
		(23 "Eco2.User" user "User.Eco2")
		(25 "Edge.Cuts" user "Board Geometry/Outline")
		(27 "Margin" user)
		(31 "F.CrtYd" user "Package Geometry/Place Bound Top")
		(29 "B.CrtYd" user "Package Geometry/Place Bound Bottom")
		(35 "F.Fab" user "Ref Des/Assembly Top")
		(33 "B.Fab" user "Ref Des/Assembly Bottom")
	)
	(footprint ""
		(layer "F.Cu")
		(at 430.276 -41.783 180)
		(property "Reference" "R98"
			(at 0 0 180)
			(layer "F.SilkS")
			(hide yes)
			(effects
				(font
					(size 1.27 1.27)
				)
			)
		)
		(property "Value" ""
			(at 0 0 180)
			(layer "F.Fab")
			(effects
				(font
					(size 1.27 1.27)
				)
			)
		)
		(duplicate_pad_numbers_are_jumpers no)
		(fp_line
			(start 0.7874 0.4064)
			(end -0.7874 0.4064)
			(stroke
				(width 0.1524)
				(type default)
			)
			(layer "F.SilkS")
		)
		(fp_line
			(start 0.7874 -0.4064)
			(end 0.7874 0.4064)
			(stroke
				(width 0.1524)
				(type default)
			)
			(layer "F.SilkS")
		)
		(fp_line
			(start -0.7874 0.4064)
			(end -0.7874 -0.4064)
			(stroke
				(width 0.1524)
				(type default)
			)
			(layer "F.SilkS")
		)
		(fp_line
			(start -0.7874 -0.4064)
			(end 0.7874 -0.4064)
			(stroke
				(width 0.1524)
				(type default)
			)
			(layer "F.SilkS")
		)
		(fp_line
			(start 0.67945 0.3048)
			(end 0.120396 0.3048)
			(stroke
				(width 0.1)
				(type default)
			)
			(layer "F.Fab")
		)
		(fp_line
			(start 0.67945 -0.3048)
			(end 0.67945 0.3048)
			(stroke
				(width 0.1)
				(type default)
			)
			(layer "F.Fab")
		)
		(fp_line
			(start 0.12065 -0.2794)
			(end 0.12065 -0.3048)
			(stroke
				(width 0.1)
				(type default)
			)
			(layer "F.Fab")
		)
		(fp_line
			(start 0.12065 -0.3048)
			(end 0.67945 -0.3048)
			(stroke
				(width 0.1)
				(type default)
			)
			(layer "F.Fab")
		)
		(fp_line
			(start 0.120396 0.3048)
			(end 0.120396 0.2794)
			(stroke
				(width 0.1)
				(type default)
			)
			(layer "F.Fab")
		)
		(fp_line
			(start 0.120396 0.2794)
			(end -0.12065 0.2794)
			(stroke
				(width 0.1)
				(type default)
			)
			(layer "F.Fab")
		)
		(fp_line
			(start -0.12065 0.3048)
			(end -0.67945 0.3048)
			(stroke
				(width 0.1)
				(type default)
			)
			(layer "F.Fab")
		)
		(fp_line
			(start -0.12065 0.2794)
			(end -0.12065 0.3048)
			(stroke
				(width 0.1)
				(type default)
			)
			(layer "F.Fab")
		)
		(fp_line
			(start -0.12065 -0.2794)
			(end 0.12065 -0.2794)
			(stroke
				(width 0.1)
				(type default)
			)
			(layer "F.Fab")
		)
		(fp_line
			(start -0.12065 -0.305054)
			(end -0.12065 -0.2794)
			(stroke
				(width 0.1)
				(type default)
			)
			(layer "F.Fab")
		)
		(fp_line
			(start -0.67945 0.3048)
			(end -0.67945 -0.305054)
			(stroke
				(width 0.1)
				(type default)
			)
			(layer "F.Fab")
		)
		(fp_line
			(start -0.67945 -0.305054)
			(end -0.12065 -0.305054)
			(stroke
				(width 0.1)
				(type default)
			)
			(layer "F.Fab")
		)
		(pad "1" smd circle
			(at -0.40005 0 180)
			(size 0 0)
			(layers "F.Cu" "F.Mask" "F.Paste")
			(net "P3V3_AUX")
		)
		(pad "2" smd circle
			(at 0.40005 0 180)
			(size 0 0)
			(layers "F.Cu" "F.Mask" "F.Paste")
			(net "SKU_ID_0")
		)
	)
	(footprint ""
		(layer "F.Cu")
		(at 209.7786 -91.9988 180)
		(property "Reference" "JP6"
			(at 1.1176 -3.25247 0)
			(unlocked yes)
			(layer "F.SilkS")
			(effects
				(font
					(size 0.7874 0.5842)
					(thickness 0.1524)
				)
				(justify left)
			)
		)
		(property "Value" ""
			(at 0 0 180)
			(layer "F.Fab")
			(effects
				(font
					(size 1.27 1.27)
				)
			)
		)
		(duplicate_pad_numbers_are_jumpers no)
		(fp_line
			(start 1.234948 6.415024)
			(end -1.234948 6.415024)
			(stroke
				(width 0.1524)
				(type default)
			)
			(layer "F.SilkS")
		)
		(fp_line
			(start 1.234948 -1.335024)
			(end 1.234948 6.415024)
			(stroke
				(width 0.1524)
				(type default)
			)
			(layer "F.SilkS")
		)
		(fp_line
			(start -1.234948 6.415024)
			(end -1.234948 -1.335024)
			(stroke
				(width 0.1524)
				(type default)
			)
			(layer "F.SilkS")
		)
		(fp_line
			(start -1.234948 -1.335024)
			(end 1.234948 -1.335024)
			(stroke
				(width 0.1524)
				(type default)
			)
			(layer "F.SilkS")
		)
		(fp_poly
			(pts
				(xy 0.508 -2.530348) (xy -0.508 -2.530348) (xy 0 -1.514348)
			)
			(stroke
				(width 0)
				(type default)
			)
			(fill yes)
			(layer "F.SilkS")
		)
		(fp_line
			(start 1.234948 6.415024)
			(end -1.234948 6.415024)
			(stroke
				(width 0.1)
				(type default)
			)
			(layer "F.Fab")
		)
		(fp_line
			(start 1.234948 -1.335024)
			(end 1.234948 6.415024)
			(stroke
				(width 0.1)
				(type default)
			)
			(layer "F.Fab")
		)
		(fp_line
			(start -1.234948 6.415024)
			(end -1.234948 -1.335024)
			(stroke
				(width 0.1)
				(type default)
			)
			(layer "F.Fab")
		)
		(fp_line
			(start -1.234948 -1.335024)
			(end 1.234948 -1.335024)
			(stroke
				(width 0.1)
				(type default)
			)
			(layer "F.Fab")
		)
		(fp_poly
			(pts
				(xy 0.508 -2.530348) (xy -0.508 -2.530348) (xy 0 -1.514348)
			)
			(stroke
				(width 0)
				(type default)
			)
			(fill yes)
			(layer "F.Fab")
		)
		(fp_text user "3"
			(at -0.009652 6.5659 90)
			(unlocked yes)
			(layer "F.SilkS")
			(effects
				(font
					(size 0.7874 0.5842)
					(thickness 0.1524)
				)
				(justify left)
			)
		)
		(fp_text user "3"
			(at -0.00127 6.640576 90)
			(unlocked yes)
			(layer "B.SilkS")
			(effects
				(font
					(size 0.7874 0.5842)
					(thickness 0.1524)
				)
				(justify left mirror)
			)
		)
		(fp_text user "1"
			(at -0.00127 -0.954024 90)
			(unlocked yes)
			(layer "B.SilkS")
			(effects
				(font
					(size 0.7874 0.5842)
					(thickness 0.1524)
				)
				(justify left mirror)
			)
		)
		(fp_text user "3"
			(at -0.00127 6.640576 90)
			(unlocked yes)
			(layer "B.Fab")
			(effects
				(font
					(size 0.7874 0.5842)
					(thickness 0.1524)
				)
				(justify left mirror)
			)
		)
		(fp_text user "1"
			(at -0.00127 -0.954024 90)
			(unlocked yes)
			(layer "B.Fab")
			(effects
				(font
					(size 0.7874 0.5842)
					(thickness 0.1524)
				)
				(justify left mirror)
			)
		)
		(fp_text user "3"
			(at -0.009652 6.5659 90)
			(unlocked yes)
			(layer "F.Fab")
			(effects
				(font
					(size 0.7874 0.5842)
					(thickness 0.1524)
				)
				(justify left)
			)
		)
		(pad "1" thru_hole rect
			(at 0 0 90)
			(size 1.6764 1.6764)
			(drill 1.1684)
			(layers "*.Cu" "*.Mask")
			(remove_unused_layers no)
			(net "TP_P52V_HS2_EN")
			(clearance 0)
			(padstack
				(mode front_inner_back)
				(layer "Inner"
					(shape circle)
					(size 1.6764 1.6764)
					(clearance 0)
				)
				(layer "B.Cu"
					(shape rect)
					(size 1.6764 1.6764)
					(clearance 0)
				)
			)
		)
		(pad "2" thru_hole circle
			(at 0 2.54 90)
			(size 1.6764 1.6764)
			(drill 1.1684)
			(layers "*.Cu" "*.Mask")
			(remove_unused_layers no)
			(net "GPU_HSC2_BUF_EN_N")
			(clearance 0)
		)
		(pad "3" thru_hole circle
			(at 0 5.08 90)
			(size 1.6764 1.6764)
			(drill 1.1684)
			(layers "*.Cu" "*.Mask")
			(remove_unused_layers no)
			(net "GND")
			(clearance 0)
		)
	)
	(footprint ""
		(layer "F.Cu")
		(at 42.36339 -119.38)
		(property "Reference" "PC36"
			(at 6.04901 -4.79933 0)
			(unlocked yes)
			(layer "F.SilkS")
			(effects
				(font
					(size 0.7874 0.5842)
					(thickness 0.1524)
				)
				(justify left)
			)
		)
		(property "Value" ""
			(at 0 0 0)
			(layer "F.Fab")
			(effects
				(font
					(size 1.27 1.27)
				)
			)
		)
		(duplicate_pad_numbers_are_jumpers no)
		(fp_line
			(start -9.253728 3.750056)
			(end 9.249918 3.750056)
			(stroke
				(width 0.1524)
				(type default)
			)
			(layer "F.SilkS")
		)
		(fp_line
			(start 0 3.750056)
			(end -9.253728 3.750056)
			(stroke
				(width 0.1524)
				(type default)
			)
			(layer "F.SilkS")
		)
		(fp_circle
			(center 0 3.750056)
			(end 9.249918 3.750056)
			(stroke
				(width 0.1524)
				(type default)
			)
			(fill no)
			(layer "F.SilkS")
		)
		(fp_poly
			(pts
				(arc
					(start 9.249918 3.750056)
					(mid 0 12.999974)
					(end -9.249918 3.750056)
				)
			)
			(stroke
				(width 0)
				(type default)
			)
			(fill yes)
			(layer "F.SilkS")
		)
		(fp_circle
			(center 0 3.750056)
			(end 9.249918 3.750056)
			(stroke
				(width 0.1)
				(type default)
			)
			(fill no)
			(layer "F.Fab")
		)
		(pad "1" thru_hole rect
			(at 0 0)
			(size 1.778 1.778)
			(drill 1.27)
			(layers "*.Cu" "*.Mask")
			(remove_unused_layers no)
			(net "P52V_HS2")
			(clearance 0)
			(padstack
				(mode front_inner_back)
				(layer "Inner"
					(shape circle)
					(size 1.778 1.778)
					(clearance 0)
				)
				(layer "B.Cu"
					(shape rect)
					(size 1.778 1.778)
					(clearance 0)
				)
			)
		)
		(pad "2" thru_hole circle
			(at 0 7.500112)
			(size 1.778 1.778)
			(drill 1.27)
			(layers "*.Cu" "*.Mask")
			(remove_unused_layers no)
			(net "GND")
			(clearance 0)
		)
	)
	(footprint ""
		(layer "F.Cu")
		(at 100.000308 -87.499952 180)
		(property "Reference" "H5"
			(at 0.686308 10.390378 0)
			(unlocked yes)
			(layer "F.SilkS")
			(effects
				(font
					(size 0.7874 0.5842)
					(thickness 0.1524)
				)
				(justify left)
			)
		)
		(property "Value" ""
			(at 0 0 180)
			(layer "F.Fab")
			(effects
				(font
					(size 1.27 1.27)
				)
			)
		)
		(duplicate_pad_numbers_are_jumpers no)
		(pad "1" thru_hole oval
			(at 0 0 180)
			(size 9.017 14.0208)
			(drill 3.0226
				(offset 0 2.499868)
			)
			(layers "*.Cu" "*.Mask")
			(remove_unused_layers no)
			(net "GND")
			(clearance -1.500378)
			(padstack
				(mode front_inner_back)
				(layer "Inner"
					(shape circle)
					(size 0 0)
					(clearance 0)
				)
				(layer "B.Cu"
					(shape oval)
					(size 9.017 14.0208)
					(offset 0 2.499868)
					(clearance -1.500378)
				)
			)
		)
	)
	(footprint ""
		(layer "F.Cu")
		(at 49.85639 -30.226 180)
		(property "Reference" "PQ18"
			(at -0.56261 2.51333 0)
			(unlocked yes)
			(layer "F.SilkS")
			(effects
				(font
					(size 0.7874 0.5842)
					(thickness 0.1524)
				)
				(justify left)
			)
		)
		(property "Value" ""
			(at 0 0 180)
			(layer "F.Fab")
			(effects
				(font
					(size 1.27 1.27)
				)
			)
		)
		(duplicate_pad_numbers_are_jumpers no)
		(fp_line
			(start 1.905 1.651)
			(end -1.905 1.651)
			(stroke
				(width 0.1524)
				(type default)
			)
			(layer "F.SilkS")
		)
		(fp_line
			(start 1.905 -1.651)
			(end 1.905 1.651)
			(stroke
				(width 0.1524)
				(type default)
			)
			(layer "F.SilkS")
		)
		(fp_line
			(start -1.905 1.651)
			(end -1.905 -1.651)
			(stroke
				(width 0.1524)
				(type default)
			)
			(layer "F.SilkS")
		)
		(fp_line
			(start -1.905 -1.651)
			(end 1.905 -1.651)
			(stroke
				(width 0.1524)
				(type default)
			)
			(layer "F.SilkS")
		)
		(fp_line
			(start 1.249934 0.219964)
			(end 0.6985 0.219964)
			(stroke
				(width 0.1)
				(type default)
			)
			(layer "F.Fab")
		)
		(fp_line
			(start 1.249934 -0.219964)
			(end 1.249934 0.219964)
			(stroke
				(width 0.1)
				(type default)
			)
			(layer "F.Fab")
		)
		(fp_line
			(start 0.6985 1.524)
			(end -0.649986 1.524)
			(stroke
				(width 0.1)
				(type default)
			)
			(layer "F.Fab")
		)
		(fp_line
			(start 0.6985 0.219964)
			(end 0.6985 1.524)
			(stroke
				(width 0.1)
				(type default)
			)
			(layer "F.Fab")
		)
		(fp_line
			(start 0.6985 -0.219964)
			(end 1.249934 -0.219964)
			(stroke
				(width 0.1)
				(type default)
			)
			(layer "F.Fab")
		)
		(fp_line
			(start 0.6985 -1.524)
			(end 0.6985 -0.219964)
			(stroke
				(width 0.1)
				(type default)
			)
			(layer "F.Fab")
		)
		(fp_line
			(start -0.649986 1.524)
			(end -0.649986 1.169924)
			(stroke
				(width 0.1)
				(type default)
			)
			(layer "F.Fab")
		)
		(fp_line
			(start -0.649986 1.169924)
			(end -1.249934 1.169924)
			(stroke
				(width 0.1)
				(type default)
			)
			(layer "F.Fab")
		)
		(fp_line
			(start -0.649986 -1.169924)
			(end -0.649986 -1.524)
			(stroke
				(width 0.1)
				(type default)
			)
			(layer "F.Fab")
		)
		(fp_line
			(start -0.649986 -1.524)
			(end 0.6985 -1.524)
			(stroke
				(width 0.1)
				(type default)
			)
			(layer "F.Fab")
		)
		(fp_line
			(start -0.6985 0.729996)
			(end -0.6985 -0.729996)
			(stroke
				(width 0.1)
				(type default)
			)
			(layer "F.Fab")
		)
		(fp_line
			(start -0.6985 -0.729996)
			(end -1.249934 -0.729996)
			(stroke
				(width 0.1)
				(type default)
			)
			(layer "F.Fab")
		)
		(fp_line
			(start -1.249934 1.169924)
			(end -1.249934 0.729996)
			(stroke
				(width 0.1)
				(type default)
			)
			(layer "F.Fab")
		)
		(fp_line
			(start -1.249934 0.729996)
			(end -0.6985 0.729996)
			(stroke
				(width 0.1)
				(type default)
			)
			(layer "F.Fab")
		)
		(fp_line
			(start -1.249934 -0.729996)
			(end -1.249934 -1.169924)
			(stroke
				(width 0.1)
				(type default)
			)
			(layer "F.Fab")
		)
		(fp_line
			(start -1.249934 -1.169924)
			(end -0.649986 -1.169924)
			(stroke
				(width 0.1)
				(type default)
			)
			(layer "F.Fab")
		)
		(pad "B" smd rect
			(at -1.1176 -1.016 90)
			(size 1.016 1.27)
			(layers "F.Cu" "F.Mask" "F.Paste")
			(net "P52V_HS2_EN_DISCHARGE_VBE")
		)
		(pad "C" smd rect
			(at 1.1176 0 90)
			(size 1.016 1.27)
			(layers "F.Cu" "F.Mask" "F.Paste")
			(net "P52V_HS2_EN_DISCHARGE_N")
		)
		(pad "E" smd rect
			(at -1.1176 1.016 90)
			(size 1.016 1.27)
			(layers "F.Cu" "F.Mask" "F.Paste")
			(net "GND")
		)
	)
	(footprint ""
		(layer "F.Cu")
		(at 449.326 -34.163)
		(property "Reference" "C3"
			(at 0 0 0)
			(layer "F.SilkS")
			(hide yes)
			(effects
				(font
					(size 1.27 1.27)
				)
			)
		)
		(property "Value" ""
			(at 0 0 0)
			(layer "F.Fab")
			(effects
				(font
					(size 1.27 1.27)
				)
			)
		)
		(duplicate_pad_numbers_are_jumpers no)
		(fp_line
			(start -0.7874 -0.4064)
			(end 0.7874 -0.4064)
			(stroke
				(width 0.1524)
				(type default)
			)
			(layer "F.SilkS")
		)
		(fp_line
			(start -0.7874 0.4064)
			(end -0.7874 -0.4064)
			(stroke
				(width 0.1524)
				(type default)
			)
			(layer "F.SilkS")
		)
		(fp_line
			(start 0.7874 -0.4064)
			(end 0.7874 0.4064)
			(stroke
				(width 0.1524)
				(type default)
			)
			(layer "F.SilkS")
		)
		(fp_line
			(start 0.7874 0.4064)
			(end -0.7874 0.4064)
			(stroke
				(width 0.1524)
				(type default)
			)
			(layer "F.SilkS")
		)
		(fp_line
			(start -0.67945 -0.305054)
			(end -0.12065 -0.305054)
			(stroke
				(width 0.1)
				(type default)
			)
			(layer "F.Fab")
		)
		(fp_line
			(start -0.67945 0.3048)
			(end -0.67945 -0.305054)
			(stroke
				(width 0.1)
				(type default)
			)
			(layer "F.Fab")
		)
		(fp_line
			(start -0.12065 -0.305054)
			(end -0.12065 -0.2794)
			(stroke
				(width 0.1)
				(type default)
			)
			(layer "F.Fab")
		)
		(fp_line
			(start -0.12065 -0.2794)
			(end 0.12065 -0.2794)
			(stroke
				(width 0.1)
				(type default)
			)
			(layer "F.Fab")
		)
		(fp_line
			(start -0.12065 0.2794)
			(end -0.12065 0.3048)
			(stroke
				(width 0.1)
				(type default)
			)
			(layer "F.Fab")
		)
		(fp_line
			(start -0.12065 0.3048)
			(end -0.67945 0.3048)
			(stroke
				(width 0.1)
				(type default)
			)
			(layer "F.Fab")
		)
		(fp_line
			(start 0.120396 0.2794)
			(end -0.12065 0.2794)
			(stroke
				(width 0.1)
				(type default)
			)
			(layer "F.Fab")
		)
		(fp_line
			(start 0.120396 0.3048)
			(end 0.120396 0.2794)
			(stroke
				(width 0.1)
				(type default)
			)
			(layer "F.Fab")
		)
		(fp_line
			(start 0.12065 -0.3048)
			(end 0.67945 -0.3048)
			(stroke
				(width 0.1)
				(type default)
			)
			(layer "F.Fab")
		)
		(fp_line
			(start 0.12065 -0.2794)
			(end 0.12065 -0.3048)
			(stroke
				(width 0.1)
				(type default)
			)
			(layer "F.Fab")
		)
		(fp_line
			(start 0.67945 -0.3048)
			(end 0.67945 0.3048)
			(stroke
				(width 0.1)
				(type default)
			)
			(layer "F.Fab")
		)
		(fp_line
			(start 0.67945 0.3048)
			(end 0.120396 0.3048)
			(stroke
				(width 0.1)
				(type default)
			)
			(layer "F.Fab")
		)
		(pad "1" smd circle
			(at -0.40005 0)
			(size 0 0)
			(layers "F.Cu" "F.Mask" "F.Paste")
			(net "P3V3_AUX")
		)
		(pad "2" smd circle
			(at 0.40005 0)
			(size 0 0)
			(layers "F.Cu" "F.Mask" "F.Paste")
			(net "GND")
		)
	)
	(footprint ""
		(layer "F.Cu")
		(at 77.851 -55.4736)
		(property "Reference" "DM1"
			(at 0 0 0)
			(layer "F.SilkS")
			(hide yes)
			(effects
				(font
					(size 1.27 1.27)
				)
			)
		)
		(property "Value" ""
			(at 0 0 0)
			(layer "F.Fab")
			(effects
				(font
					(size 1.27 1.27)
				)
			)
		)
		(duplicate_pad_numbers_are_jumpers no)
		(fp_line
			(start 0 -4.99999)
			(end 0 -3.47599)
			(stroke
				(width 0.1524)
				(type default)
			)
			(layer "F.SilkS")
		)
		(fp_line
			(start 0 -1.524)
			(end 0 0)
			(stroke
				(width 0.1524)
				(type default)
			)
			(layer "F.SilkS")
		)
		(fp_line
			(start 1.524 -4.99999)
			(end 0 -4.99999)
			(stroke
				(width 0.1524)
				(type default)
			)
			(layer "F.SilkS")
		)
		(fp_text user "P/N"
			(at 0.361188 -3.449828 0)
			(unlocked yes)
			(layer "F.SilkS")
			(effects
				(font
					(size 1.905 1.4224)
					(thickness 0.1524)
				)
				(justify left)
			)
		)
	)
)
